(kicad_pcb
	(version 20260206)
	(generator "pcbnew")
	(generator_version "10.0")
	(general
		(thickness 1.6)
		(legacy_teardrops no)
	)
	(paper "A4")
	(title_block
		(title "9054_F0T_PDB_BD_GPU_F_V04_1213_1550_OCP.brd")
		(comment 1 "Grand Teton / footprints 150-159 of 608")
	)
	(layers
		(0 "F.Cu" signal "TOP")
		(4 "In1.Cu" signal "GND")
		(6 "In2.Cu" signal "IN1")
		(8 "In3.Cu" signal "GND1")
		(10 "In4.Cu" signal "VCC")
		(12 "In5.Cu" signal "VCC1")
		(14 "In6.Cu" signal "GND2")
		(16 "In7.Cu" signal "IN2")
		(18 "In8.Cu" signal "GND3")
		(2 "B.Cu" signal "BOTTOM")
		(9 "F.Adhes" user "F.Adhesive")
		(11 "B.Adhes" user "B.Adhesive")
		(13 "F.Paste" user "Package Geometry/Pastemask Top")
		(15 "B.Paste" user "Package Geometry/Pastemask Bottom")
		(5 "F.SilkS" user "Ref Des/Silkscreen Top")
		(7 "B.SilkS" user "Ref Des/Silkscreen Bottom")
		(1 "F.Mask" user "Board Geometry/Soldermask Top")
		(3 "B.Mask" user "Board Geometry/Soldermask Bottom")
		(17 "Dwgs.User" user "User.Drawings")
		(19 "Cmts.User" user "User.Comments")
		(21 "Eco1.User" user "User.Eco1")
		(23 "Eco2.User" user "User.Eco2")
		(25 "Edge.Cuts" user "Board Geometry/Outline")
		(27 "Margin" user)
		(31 "F.CrtYd" user "Package Geometry/Place Bound Top")
		(29 "B.CrtYd" user "Package Geometry/Place Bound Bottom")
		(35 "F.Fab" user "Ref Des/Assembly Top")
		(33 "B.Fab" user "Ref Des/Assembly Bottom")
	)
	(footprint ""
		(layer "F.Cu")
		(at 406.146 -37.846 180)
		(property "Reference" "R40"
			(at 0 0 180)
			(layer "F.SilkS")
			(hide yes)
			(effects
				(font
					(size 1.27 1.27)
				)
			)
		)
		(property "Value" ""
			(at 0 0 180)
			(layer "F.Fab")
			(effects
				(font
					(size 1.27 1.27)
				)
			)
		)
		(duplicate_pad_numbers_are_jumpers no)
		(fp_line
			(start 2.234946 0.9271)
			(end -2.234946 0.9271)
			(stroke
				(width 0.1524)
				(type default)
			)
			(layer "F.SilkS")
		)
		(fp_line
			(start 2.234946 -0.9271)
			(end 2.234946 0.9271)
			(stroke
				(width 0.1524)
				(type default)
			)
			(layer "F.SilkS")
		)
		(fp_line
			(start -2.234946 0.9271)
			(end -2.234946 -0.9271)
			(stroke
				(width 0.1524)
				(type default)
			)
			(layer "F.SilkS")
		)
		(fp_line
			(start -2.234946 -0.9271)
			(end 2.234946 -0.9271)
			(stroke
				(width 0.1524)
				(type default)
			)
			(layer "F.SilkS")
		)
		(fp_line
			(start 1.575054 0.824992)
			(end 1.575054 -0.824992)
			(stroke
				(width 0.1)
				(type default)
			)
			(layer "F.Fab")
		)
		(fp_line
			(start 1.575054 -0.824992)
			(end -1.575054 -0.824992)
			(stroke
				(width 0.1)
				(type default)
			)
			(layer "F.Fab")
		)
		(fp_line
			(start -1.575054 0.824992)
			(end 1.575054 0.824992)
			(stroke
				(width 0.1)
				(type default)
			)
			(layer "F.Fab")
		)
		(fp_line
			(start -1.575054 -0.824992)
			(end -1.575054 0.824992)
			(stroke
				(width 0.1)
				(type default)
			)
			(layer "F.Fab")
		)
		(pad "1" smd rect
			(at -1.599946 0 180)
			(size 1.016 1.6002)
			(layers "F.Cu" "F.Mask" "F.Paste")
			(net "LED_D1_R1")
		)
		(pad "2" smd rect
			(at 1.599946 0 180)
			(size 1.016 1.6002)
			(layers "F.Cu" "F.Mask" "F.Paste")
			(net "LED_D1_R2")
		)
	)
	(footprint ""
		(layer "F.Cu")
		(at 452.0184 -62.23 -90)
		(property "Reference" "PC48"
			(at 0 0 270)
			(layer "F.SilkS")
			(hide yes)
			(effects
				(font
					(size 1.27 1.27)
				)
			)
		)
		(property "Value" ""
			(at 0 0 270)
			(layer "F.Fab")
			(effects
				(font
					(size 1.27 1.27)
				)
			)
		)
		(duplicate_pad_numbers_are_jumpers no)
		(fp_line
			(start -1.524 0.762)
			(end -1.524 -0.762)
			(stroke
				(width 0.1524)
				(type default)
			)
			(layer "F.SilkS")
		)
		(fp_line
			(start 1.524 0.762)
			(end -1.524 0.762)
			(stroke
				(width 0.1524)
				(type default)
			)
			(layer "F.SilkS")
		)
		(fp_line
			(start -1.524 -0.762)
			(end 1.524 -0.762)
			(stroke
				(width 0.1524)
				(type default)
			)
			(layer "F.SilkS")
		)
		(fp_line
			(start 1.524 -0.762)
			(end 1.524 0.762)
			(stroke
				(width 0.1524)
				(type default)
			)
			(layer "F.SilkS")
		)
		(fp_line
			(start -1.1049 0.724916)
			(end 1.1049 0.724916)
			(stroke
				(width 0.1)
				(type default)
			)
			(layer "F.Fab")
		)
		(fp_line
			(start 1.1049 0.724916)
			(end 1.1049 -0.724916)
			(stroke
				(width 0.1)
				(type default)
			)
			(layer "F.Fab")
		)
		(fp_line
			(start -1.1049 -0.724916)
			(end -1.1049 0.724916)
			(stroke
				(width 0.1)
				(type default)
			)
			(layer "F.Fab")
		)
		(fp_line
			(start 1.1049 -0.724916)
			(end -1.1049 -0.724916)
			(stroke
				(width 0.1)
				(type default)
			)
			(layer "F.Fab")
		)
		(pad "1" smd rect
			(at -0.889 0 90)
			(size 1.016 1.27)
			(layers "F.Cu" "F.Mask" "F.Paste")
			(net "P3V3_AUX")
		)
		(pad "2" smd rect
			(at 0.889 0 90)
			(size 1.016 1.27)
			(layers "F.Cu" "F.Mask" "F.Paste")
			(net "GND")
		)
	)
	(footprint ""
		(layer "F.Cu")
		(at 469.540082 -25.199848 90)
		(property "Reference" "J16"
			(at 6.523482 -1.291082 0)
			(unlocked yes)
			(layer "F.SilkS")
			(effects
				(font
					(size 0.7874 0.5842)
					(thickness 0.1524)
				)
				(justify left)
			)
		)
		(property "Value" ""
			(at 0 0 90)
			(layer "F.Fab")
			(effects
				(font
					(size 1.27 1.27)
				)
			)
		)
		(duplicate_pad_numbers_are_jumpers no)
		(fp_circle
			(center 0 0)
			(end 0 5.3848)
			(stroke
				(width 0.1524)
				(type default)
			)
			(fill no)
			(layer "F.SilkS")
		)
		(fp_line
			(start 3.999992 -2.999994)
			(end 4.000246 2.999994)
			(stroke
				(width 0.1)
				(type default)
			)
			(layer "F.Fab")
		)
		(fp_line
			(start -3.999992 2.999994)
			(end -3.999738 -2.999994)
			(stroke
				(width 0.1)
				(type default)
			)
			(layer "F.Fab")
		)
		(fp_arc
			(start -3.999738 -2.999994)
			(mid 0.000178 -4.99999)
			(end 3.999992 -2.999994)
			(stroke
				(width 0.1)
				(type default)
			)
			(layer "F.Fab")
		)
		(fp_arc
			(start 4.000246 2.999994)
			(mid 0.000178 4.99999)
			(end -3.999992 2.999994)
			(stroke
				(width 0.1)
				(type default)
			)
			(layer "F.Fab")
		)
		(pad "G1" thru_hole oval
			(at 0 -3.262376 90)
			(size 1.8796 3.1242)
			(drill oval 1.6256 2.8702)
			(layers "*.Cu" "*.Mask")
			(remove_unused_layers no)
			(net "GND")
			(clearance 0.254)
			(thermal_gap 0.254)
		)
		(pad "SCR_G1" thru_hole circle
			(at 0 0 90)
			(size 10.5156 10.5156)
			(drill 5.1562)
			(layers "*.Cu" "*.Mask")
			(remove_unused_layers no)
			(net "GND")
			(clearance 0)
		)
		(zone
			(layers "F.Cu" "B.Cu" "In1.Cu" "In2.Cu" "In3.Cu" "In4.Cu" "In5.Cu" "In6.Cu"
				"In7.Cu" "In8.Cu"
			)
			(hatch none 0.5)
			(connect_pads
				(clearance 0)
			)
			(min_thickness 0.25)
			(keepout
				(tracks not_allowed)
				(vias allowed)
				(pads allowed)
				(copperpour not_allowed)
				(footprints allowed)
			)
			(placement
				(enabled no)
				(sheetname "")
			)
			(fill
				(thermal_gap 0.5)
				(thermal_bridge_width 0.5)
				(island_removal_mode 0)
			)
			(polygon
				(pts
					(arc
						(start 542.615882 -26.850848)
						(mid 532.100282 -26.850848)
						(end 542.615882 -26.850848)
					)
				)
			)
		)
	)
	(footprint ""
		(layer "F.Cu")
		(at 429.2854 -34.1376 90)
		(property "Reference" "R58"
			(at 0 0 90)
			(layer "F.SilkS")
			(hide yes)
			(effects
				(font
					(size 1.27 1.27)
				)
			)
		)
		(property "Value" ""
			(at 0 0 90)
			(layer "F.Fab")
			(effects
				(font
					(size 1.27 1.27)
				)
			)
		)
		(duplicate_pad_numbers_are_jumpers no)
		(fp_line
			(start 0.7874 -0.4064)
			(end 0.7874 0.4064)
			(stroke
				(width 0.1524)
				(type default)
			)
			(layer "F.SilkS")
		)
		(fp_line
			(start -0.7874 -0.4064)
			(end 0.7874 -0.4064)
			(stroke
				(width 0.1524)
				(type default)
			)
			(layer "F.SilkS")
		)
		(fp_line
			(start 0.7874 0.4064)
			(end -0.7874 0.4064)
			(stroke
				(width 0.1524)
				(type default)
			)
			(layer "F.SilkS")
		)
		(fp_line
			(start -0.7874 0.4064)
			(end -0.7874 -0.4064)
			(stroke
				(width 0.1524)
				(type default)
			)
			(layer "F.SilkS")
		)
		(fp_line
			(start -0.12065 -0.305054)
			(end -0.12065 -0.2794)
			(stroke
				(width 0.1)
				(type default)
			)
			(layer "F.Fab")
		)
		(fp_line
			(start -0.67945 -0.305054)
			(end -0.12065 -0.305054)
			(stroke
				(width 0.1)
				(type default)
			)
			(layer "F.Fab")
		)
		(fp_line
			(start 0.67945 -0.3048)
			(end 0.67945 0.3048)
			(stroke
				(width 0.1)
				(type default)
			)
			(layer "F.Fab")
		)
		(fp_line
			(start 0.12065 -0.3048)
			(end 0.67945 -0.3048)
			(stroke
				(width 0.1)
				(type default)
			)
			(layer "F.Fab")
		)
		(fp_line
			(start 0.12065 -0.2794)
			(end 0.12065 -0.3048)
			(stroke
				(width 0.1)
				(type default)
			)
			(layer "F.Fab")
		)
		(fp_line
			(start -0.12065 -0.2794)
			(end 0.12065 -0.2794)
			(stroke
				(width 0.1)
				(type default)
			)
			(layer "F.Fab")
		)
		(fp_line
			(start 0.120396 0.2794)
			(end -0.12065 0.2794)
			(stroke
				(width 0.1)
				(type default)
			)
			(layer "F.Fab")
		)
		(fp_line
			(start -0.12065 0.2794)
			(end -0.12065 0.3048)
			(stroke
				(width 0.1)
				(type default)
			)
			(layer "F.Fab")
		)
		(fp_line
			(start 0.67945 0.3048)
			(end 0.120396 0.3048)
			(stroke
				(width 0.1)
				(type default)
			)
			(layer "F.Fab")
		)
		(fp_line
			(start 0.120396 0.3048)
			(end 0.120396 0.2794)
			(stroke
				(width 0.1)
				(type default)
			)
			(layer "F.Fab")
		)
		(fp_line
			(start -0.12065 0.3048)
			(end -0.67945 0.3048)
			(stroke
				(width 0.1)
				(type default)
			)
			(layer "F.Fab")
		)
		(fp_line
			(start -0.67945 0.3048)
			(end -0.67945 -0.305054)
			(stroke
				(width 0.1)
				(type default)
			)
			(layer "F.Fab")
		)
		(pad "1" smd circle
			(at -0.40005 0 90)
			(size 0 0)
			(layers "F.Cu" "F.Mask" "F.Paste")
			(net "FRU_WP_N")
		)
		(pad "2" smd circle
			(at 0.40005 0 90)
			(size 0 0)
			(layers "F.Cu" "F.Mask" "F.Paste")
			(net "GND")
		)
	)
	(footprint ""
		(layer "F.Cu")
		(at 190.000128 -16.500094 180)
		(property "Reference" "H7"
			(at 0.643128 -5.477764 0)
			(unlocked yes)
			(layer "F.SilkS")
			(effects
				(font
					(size 0.7874 0.5842)
					(thickness 0.1524)
				)
				(justify left)
			)
		)
		(property "Value" ""
			(at 0 0 180)
			(layer "F.Fab")
			(effects
				(font
					(size 1.27 1.27)
				)
			)
		)
		(duplicate_pad_numbers_are_jumpers no)
		(pad "1" thru_hole oval
			(at 0 0 180)
			(size 9.017 14.0208)
			(drill 3.0226
				(offset 0 2.499868)
			)
			(layers "*.Cu" "*.Mask")
			(remove_unused_layers no)
			(net "GND")
			(clearance -1.500378)
			(padstack
				(mode front_inner_back)
				(layer "Inner"
					(shape circle)
					(size 0 0)
					(clearance 0)
				)
				(layer "B.Cu"
					(shape oval)
					(size 9.017 14.0208)
					(offset 0 2.499868)
					(clearance -1.500378)
				)
			)
		)
	)
	(footprint ""
		(layer "F.Cu")
		(at 304.616358 -29.5402)
		(property "Reference" "PR315"
			(at -4.197858 4.68757 0)
			(unlocked yes)
			(layer "F.SilkS")
			(effects
				(font
					(size 0.7874 0.5842)
					(thickness 0.1524)
				)
				(justify left)
			)
		)
		(property "Value" ""
			(at 0 0 0)
			(layer "F.Fab")
			(effects
				(font
					(size 1.27 1.27)
				)
			)
		)
		(duplicate_pad_numbers_are_jumpers no)
		(fp_line
			(start -3.9878 -3.5814)
			(end 3.9878 -3.5814)
			(stroke
				(width 0.1524)
				(type default)
			)
			(layer "F.SilkS")
		)
		(fp_line
			(start -3.9878 3.5814)
			(end -3.9878 -3.5814)
			(stroke
				(width 0.1524)
				(type default)
			)
			(layer "F.SilkS")
		)
		(fp_line
			(start 3.9878 -3.5814)
			(end 3.9878 3.5814)
			(stroke
				(width 0.1524)
				(type default)
			)
			(layer "F.SilkS")
		)
		(fp_line
			(start 3.9878 3.5814)
			(end -3.9878 3.5814)
			(stroke
				(width 0.1524)
				(type default)
			)
			(layer "F.SilkS")
		)
		(fp_line
			(start -3.5306 -3.353054)
			(end 3.5306 -3.353054)
			(stroke
				(width 0.1)
				(type default)
			)
			(layer "F.Fab")
		)
		(fp_line
			(start -3.5306 3.353054)
			(end -3.5306 -3.353054)
			(stroke
				(width 0.1)
				(type default)
			)
			(layer "F.Fab")
		)
		(fp_line
			(start 3.5306 -3.353054)
			(end 3.5306 3.353054)
			(stroke
				(width 0.1)
				(type default)
			)
			(layer "F.Fab")
		)
		(fp_line
			(start 3.5306 3.353054)
			(end -3.5306 3.353054)
			(stroke
				(width 0.1)
				(type default)
			)
			(layer "F.Fab")
		)
		(pad "1A" smd rect
			(at -2.249932 0 180)
			(size 3.2004 6.858)
			(layers "F.Cu" "F.Mask" "F.Paste")
			(net "P52V_1")
		)
		(pad "1B" smd rect
			(at -0.776732 0)
			(size 0.254 0.508)
			(layers "F.Cu" "F.Mask" "F.Paste")
			(net "P52V_HS1_SENSE_P_R2")
		)
		(pad "2A" smd rect
			(at 2.249932 0 180)
			(size 3.2004 6.858)
			(layers "F.Cu" "F.Mask" "F.Paste")
			(net "P52V_HS1_DRAIN_2")
		)
		(pad "2B" smd rect
			(at 0.776732 0)
			(size 0.254 0.508)
			(layers "F.Cu" "F.Mask" "F.Paste")
			(net "P52V_HS1_SENSE_N_R2")
		)
	)
	(footprint ""
		(layer "F.Cu")
		(at 8.200136 -137.500106 180)
		(property "Reference" "H19"
			(at -1.007364 -6.475476 0)
			(unlocked yes)
			(layer "F.SilkS")
			(effects
				(font
					(size 0.7874 0.5842)
					(thickness 0.1524)
				)
				(justify left)
			)
		)
		(property "Value" ""
			(at 0 0 180)
			(layer "F.Fab")
			(effects
				(font
					(size 1.27 1.27)
				)
			)
		)
		(duplicate_pad_numbers_are_jumpers no)
		(pad "1" thru_hole circle
			(at 0 0 180)
			(size 10.16 10.16)
			(drill 6.4008
				(offset 0 0)
			)
			(layers "*.Cu" "*.Mask")
			(remove_unused_layers no)
			(net "GND")
			(clearance -1.6256)
			(padstack
				(mode front_inner_back)
				(layer "Inner"
					(shape circle)
					(size 10.16 10.16)
					(clearance -1.6256)
				)
				(layer "B.Cu"
					(shape oval)
					(size 10.0076 17.018)
					(offset 0 3.499866)
					(clearance -1.5494)
				)
			)
		)
	)
	(footprint ""
		(layer "F.Cu")
		(at 424.999912 -126.500128 180)
		(property "Reference" "H37"
			(at -1.021588 -5.762498 0)
			(unlocked yes)
			(layer "F.SilkS")
			(effects
				(font
					(size 0.7874 0.5842)
					(thickness 0.1524)
				)
				(justify left)
			)
		)
		(property "Value" ""
			(at 0 0 180)
			(layer "F.Fab")
			(effects
				(font
					(size 1.27 1.27)
				)
			)
		)
		(duplicate_pad_numbers_are_jumpers no)
		(pad "1" thru_hole circle
			(at 0 0 180)
			(size 10.16 10.16)
			(drill 6.4008
				(offset 0 0)
			)
			(layers "*.Cu" "*.Mask")
			(remove_unused_layers no)
			(net "GND")
			(clearance -1.6256)
			(padstack
				(mode front_inner_back)
				(layer "Inner"
					(shape circle)
					(size 10.16 10.16)
					(clearance -1.6256)
				)
				(layer "B.Cu"
					(shape oval)
					(size 10.0076 17.018)
					(offset 0 3.499866)
					(clearance -1.5494)
				)
			)
		)
	)
	(footprint ""
		(layer "F.Cu")
		(at 436.10022 -127.793496)
		(property "Reference" ""
			(at 0 0 0)
			(layer "F.SilkS")
			(hide yes)
			(effects
				(font
					(size 1.27 1.27)
				)
			)
		)
		(property "Value" ""
			(at 0 0 0)
			(layer "F.Fab")
			(effects
				(font
					(size 1.27 1.27)
				)
			)
		)
		(duplicate_pad_numbers_are_jumpers no)
		(pad "1" smd circle
			(at 0 0)
			(size 0.9906 0.9906)
			(layers "F.Cu" "F.Mask" "F.Paste")
			(net "Net_377")
		)
		(zone
			(layer "F.Cu")
			(hatch none 0.5)
			(connect_pads
				(clearance 0)
			)
			(min_thickness 0.25)
			(keepout
				(tracks not_allowed)
				(vias allowed)
				(pads allowed)
				(copperpour not_allowed)
				(footprints allowed)
			)
			(placement
				(enabled no)
				(sheetname "")
			)
			(fill
				(thermal_gap 0.5)
				(thermal_bridge_width 0.5)
				(island_removal_mode 0)
			)
			(polygon
				(pts
					(arc
						(start 437.72582 -127.793496)
						(mid 434.47462 -127.793496)
						(end 437.72582 -127.793496)
					)
				)
			)
		)
	)
	(footprint ""
		(layer "F.Cu")
		(at 334.631284 -72.898 -90)
		(property "Reference" "PR474"
			(at 0 0 270)
			(layer "F.SilkS")
			(hide yes)
			(effects
				(font
					(size 1.27 1.27)
				)
			)
		)
		(property "Value" ""
			(at 0 0 270)
			(layer "F.Fab")
			(effects
				(font
					(size 1.27 1.27)
				)
			)
		)
		(duplicate_pad_numbers_are_jumpers no)
		(fp_line
			(start -1.2954 0.5842)
			(end -1.2954 -0.5842)
			(stroke
				(width 0.1524)
				(type default)
			)
			(layer "F.SilkS")
		)
		(fp_line
			(start 1.2954 0.5842)
			(end -1.2954 0.5842)
			(stroke
				(width 0.1524)
				(type default)
			)
			(layer "F.SilkS")
		)
		(fp_line
			(start -1.2954 -0.5842)
			(end 1.2954 -0.5842)
			(stroke
				(width 0.1524)
				(type default)
			)
			(layer "F.SilkS")
		)
		(fp_line
			(start 1.2954 -0.5842)
			(end 1.2954 0.5842)
			(stroke
				(width 0.1524)
				(type default)
			)
			(layer "F.SilkS")
		)
		(fp_line
			(start -0.8636 0.4572)
			(end -0.8636 0.4318)
			(stroke
				(width 0.1)
				(type default)
			)
			(layer "F.Fab")
		)
		(fp_line
			(start 0.8636 0.4572)
			(end -0.8636 0.4572)
			(stroke
				(width 0.1)
				(type default)
			)
			(layer "F.Fab")
		)
		(fp_line
			(start -0.8636 0.4318)
			(end -0.8636 0.4064)
			(stroke
				(width 0.1)
				(type default)
			)
			(layer "F.Fab")
		)
		(fp_line
			(start -1.1938 0.4064)
			(end -1.1938 -0.406654)
			(stroke
				(width 0.1)
				(type default)
			)
			(layer "F.Fab")
		)
		(fp_line
			(start -0.8636 0.4064)
			(end -1.1938 0.4064)
			(stroke
				(width 0.1)
				(type default)
			)
			(layer "F.Fab")
		)
		(fp_line
			(start 0.8636 0.4064)
			(end 0.8636 0.4572)
			(stroke
				(width 0.1)
				(type default)
			)
			(layer "F.Fab")
		)
		(fp_line
			(start 1.1938 0.4064)
			(end 0.8636 0.4064)
			(stroke
				(width 0.1)
				(type default)
			)
			(layer "F.Fab")
		)
		(fp_line
			(start -1.1938 -0.406654)
			(end -0.8636 -0.406654)
			(stroke
				(width 0.1)
				(type default)
			)
			(layer "F.Fab")
		)
		(fp_line
			(start -0.8636 -0.406654)
			(end -0.8636 -0.4572)
			(stroke
				(width 0.1)
				(type default)
			)
			(layer "F.Fab")
		)
		(fp_line
			(start 0.8636 -0.406654)
			(end 1.1938 -0.406654)
			(stroke
				(width 0.1)
				(type default)
			)
			(layer "F.Fab")
		)
		(fp_line
			(start 1.1938 -0.406654)
			(end 1.1938 0.4064)
			(stroke
				(width 0.1)
				(type default)
			)
			(layer "F.Fab")
		)
		(fp_line
			(start -0.8636 -0.4572)
			(end 0.8636 -0.4572)
			(stroke
				(width 0.1)
				(type default)
			)
			(layer "F.Fab")
		)
		(fp_line
			(start 0.8636 -0.4572)
			(end 0.8636 -0.406654)
			(stroke
				(width 0.1)
				(type default)
			)
			(layer "F.Fab")
		)
		(pad "1" smd rect
			(at -0.7366 0 180)
			(size 0.7112 0.8128)
			(layers "F.Cu" "F.Mask" "F.Paste")
			(net "P52V_HS1_GATE1_R")
		)
		(pad "2" smd rect
			(at 0.7366 0 180)
			(size 0.7112 0.8128)
			(layers "F.Cu" "F.Mask" "F.Paste")
			(net "P52V_HS1_GATE1")
		)
	)
)
